# S9S_MB_2U (Grand Teton) — schematic netlist excerpt (pin names and nets, part order shuffled) for the footprints in the layout excerpt that follows; sources: Cadence DE-HDL packaged netlist, KiCad conversion of 03242023_DA0F0TMBIJ0_F0T_Motherboard_J_brd_V01_OCP.brd

PR147  Q_RES  2.2 1% CHIP  pkg 0402LF  page 268 : A = PVCCIN_CPU0_PVCC ; B = PVCCIN_CPU0_VDD3
PC290_P0_4  Q_CAP  22UF 4V 20% X6S  pkg C0805  page 268 : A = PVCCIN_CPU0 ; B = GND
R1853  Q_RES  0 5% CHIP  pkg 0402LF  page 213 : A = VIRTUAL_RESEAT_FPGA_R_N ; B = VIRTUAL_RESEAT_FPGA_N

(kicad_pcb
	(version 20260206)
	(generator "pcbnew")
	(generator_version "10.0")
	(general
		(thickness 1.6)
		(legacy_teardrops no)
	)
	(paper "A4")
	(title_block
		(title "03242023_DA0F0TMBIJ0_F0T_Motherboard_J_brd_V01_OCP.brd")
		(comment 1 "Grand Teton / footprints 5488-5490 of 6105")
	)
	(layers
		(0 "F.Cu" signal "TOP")
		(4 "In1.Cu" signal "GND")
		(6 "In2.Cu" signal "IN1")
		(8 "In3.Cu" signal "GND1")
		(10 "In4.Cu" signal "IN2")
		(12 "In5.Cu" signal "GND2")
		(14 "In6.Cu" signal "IN3")
		(16 "In7.Cu" signal "GND3")
		(18 "In8.Cu" signal "VCC")
		(20 "In9.Cu" signal "VCC1")
		(22 "In10.Cu" signal "GND4")
		(24 "In11.Cu" signal "IN4")
		(26 "In12.Cu" signal "GND5")
		(28 "In13.Cu" signal "IN5")
		(30 "In14.Cu" signal "GND6")
		(32 "In15.Cu" signal "IN6")
		(34 "In16.Cu" signal "GND7")
		(2 "B.Cu" signal "BOTTOM")
		(9 "F.Adhes" user "F.Adhesive")
		(11 "B.Adhes" user "B.Adhesive")
		(13 "F.Paste" user "Package Geometry/Pastemask Top")
		(15 "B.Paste" user "Package Geometry/Pastemask Bottom")
		(5 "F.SilkS" user "Ref Des/Silkscreen Top")
		(7 "B.SilkS" user "Ref Des/Silkscreen Bottom")
		(1 "F.Mask" user "Board Geometry/Soldermask Top")
		(3 "B.Mask" user "Board Geometry/Soldermask Bottom")
		(17 "Dwgs.User" user "User.Drawings")
		(19 "Cmts.User" user "User.Comments")
		(21 "Eco1.User" user "User.Eco1")
		(23 "Eco2.User" user "User.Eco2")
		(25 "Edge.Cuts" user "Board Geometry/Outline")
		(27 "Margin" user)
		(31 "F.CrtYd" user "Package Geometry/Place Bound Top")
		(29 "B.CrtYd" user "Package Geometry/Place Bound Bottom")
		(35 "F.Fab" user "Ref Des/Assembly Top")
		(33 "B.Fab" user "Ref Des/Assembly Bottom")
	)
	(footprint ""
		(layer "B.Cu")
		(at 164.64788 -107.025948)
		(property "Reference" "R1853"
			(at 0 0 0)
			(layer "B.SilkS")
			(hide yes)
			(effects
				(font
					(size 1.27 1.27)
				)
				(justify mirror)
			)
		)
		(property "Value" ""
			(at 0 0 0)
			(layer "B.Fab")
			(effects
				(font
					(size 1.27 1.27)
				)
				(justify mirror)
			)
		)
		(duplicate_pad_numbers_are_jumpers no)
		(fp_line
			(start -0.7874 -0.4064)
			(end -0.7874 0.4064)
			(stroke
				(width 0.1524)
				(type default)
			)
			(layer "B.SilkS")
		)
		(fp_line
			(start -0.7874 0.4064)
			(end 0.7874 0.4064)
			(stroke
				(width 0.1524)
				(type default)
			)
			(layer "B.SilkS")
		)
		(fp_line
			(start 0.7874 -0.4064)
			(end -0.7874 -0.4064)
			(stroke
				(width 0.1524)
				(type default)
			)
			(layer "B.SilkS")
		)
		(fp_line
			(start 0.7874 0.4064)
			(end 0.7874 -0.4064)
			(stroke
				(width 0.1524)
				(type default)
			)
			(layer "B.SilkS")
		)
		(fp_line
			(start -0.67945 -0.3048)
			(end -0.67945 0.3048)
			(stroke
				(width 0.1)
				(type default)
			)
			(layer "B.Fab")
		)
		(fp_line
			(start -0.67945 0.3048)
			(end -0.120396 0.3048)
			(stroke
				(width 0.1)
				(type default)
			)
			(layer "B.Fab")
		)
		(fp_line
			(start -0.12065 -0.3048)
			(end -0.67945 -0.3048)
			(stroke
				(width 0.1)
				(type default)
			)
			(layer "B.Fab")
		)
		(fp_line
			(start -0.12065 -0.2794)
			(end -0.12065 -0.3048)
			(stroke
				(width 0.1)
				(type default)
			)
			(layer "B.Fab")
		)
		(fp_line
			(start -0.120396 0.2794)
			(end 0.12065 0.2794)
			(stroke
				(width 0.1)
				(type default)
			)
			(layer "B.Fab")
		)
		(fp_line
			(start -0.120396 0.3048)
			(end -0.120396 0.2794)
			(stroke
				(width 0.1)
				(type default)
			)
			(layer "B.Fab")
		)
		(fp_line
			(start 0.12065 -0.305054)
			(end 0.12065 -0.2794)
			(stroke
				(width 0.1)
				(type default)
			)
			(layer "B.Fab")
		)
		(fp_line
			(start 0.12065 -0.2794)
			(end -0.12065 -0.2794)
			(stroke
				(width 0.1)
				(type default)
			)
			(layer "B.Fab")
		)
		(fp_line
			(start 0.12065 0.2794)
			(end 0.12065 0.3048)
			(stroke
				(width 0.1)
				(type default)
			)
			(layer "B.Fab")
		)
		(fp_line
			(start 0.12065 0.3048)
			(end 0.67945 0.3048)
			(stroke
				(width 0.1)
				(type default)
			)
			(layer "B.Fab")
		)
		(fp_line
			(start 0.67945 -0.305054)
			(end 0.12065 -0.305054)
			(stroke
				(width 0.1)
				(type default)
			)
			(layer "B.Fab")
		)
		(fp_line
			(start 0.67945 0.3048)
			(end 0.67945 -0.305054)
			(stroke
				(width 0.1)
				(type default)
			)
			(layer "B.Fab")
		)
		(pad "1" smd circle
			(at 0.40005 0 180)
			(size 0 0)
			(layers "B.Cu" "B.Mask" "B.Paste")
			(net "VIRTUAL_RESEAT_FPGA_R_N")
		)
		(pad "2" smd circle
			(at -0.40005 0 180)
			(size 0 0)
			(layers "B.Cu" "B.Mask" "B.Paste")
			(net "VIRTUAL_RESEAT_FPGA_N")
		)
	)
	(footprint ""
		(layer "B.Cu")
		(at 368.767868 -324.911466 -90)
		(property "Reference" "PC290_P0_4"
			(at 0 0 90)
			(layer "B.SilkS")
			(hide yes)
			(effects
				(font
					(size 1.27 1.27)
				)
				(justify mirror)
			)
		)
		(property "Value" ""
			(at 0 0 90)
			(layer "B.Fab")
			(effects
				(font
					(size 1.27 1.27)
				)
				(justify mirror)
			)
		)
		(duplicate_pad_numbers_are_jumpers no)
		(fp_line
			(start -1.524 0.762)
			(end 1.524 0.762)
			(stroke
				(width 0.1524)
				(type default)
			)
			(layer "B.SilkS")
		)
		(fp_line
			(start 1.524 0.762)
			(end 1.524 -0.762)
			(stroke
				(width 0.1524)
				(type default)
			)
			(layer "B.SilkS")
		)
		(fp_line
			(start -1.524 -0.762)
			(end -1.524 0.762)
			(stroke
				(width 0.1524)
				(type default)
			)
			(layer "B.SilkS")
		)
		(fp_line
			(start 1.524 -0.762)
			(end -1.524 -0.762)
			(stroke
				(width 0.1524)
				(type default)
			)
			(layer "B.SilkS")
		)
		(fp_line
			(start -1.1049 0.724916)
			(end -1.1049 -0.724916)
			(stroke
				(width 0.1)
				(type default)
			)
			(layer "B.Fab")
		)
		(fp_line
			(start 1.1049 0.724916)
			(end -1.1049 0.724916)
			(stroke
				(width 0.1)
				(type default)
			)
			(layer "B.Fab")
		)
		(fp_line
			(start -1.1049 -0.724916)
			(end 1.1049 -0.724916)
			(stroke
				(width 0.1)
				(type default)
			)
			(layer "B.Fab")
		)
		(fp_line
			(start 1.1049 -0.724916)
			(end 1.1049 0.724916)
			(stroke
				(width 0.1)
				(type default)
			)
			(layer "B.Fab")
		)
		(pad "1" smd rect
			(at 0.889 0 270)
			(size 1.016 1.27)
			(layers "B.Cu" "B.Mask" "B.Paste")
			(net "PVCCIN_CPU0")
		)
		(pad "2" smd rect
			(at -0.889 0 270)
			(size 1.016 1.27)
			(layers "B.Cu" "B.Mask" "B.Paste")
			(net "GND")
		)
	)
	(footprint ""
		(layer "B.Cu")
		(at 358.861868 -334.703166 -90)
		(property "Reference" "PR147"
			(at 0 0 90)
			(layer "B.SilkS")
			(hide yes)
			(effects
				(font
					(size 1.27 1.27)
				)
				(justify mirror)
			)
		)
		(property "Value" ""
			(at 0 0 90)
			(layer "B.Fab")
			(effects
				(font
					(size 1.27 1.27)
				)
				(justify mirror)
			)
		)
		(duplicate_pad_numbers_are_jumpers no)
		(fp_line
			(start -0.7874 0.4064)
			(end 0.7874 0.4064)
			(stroke
				(width 0.1524)
				(type default)
			)
			(layer "B.SilkS")
		)
		(fp_line
			(start 0.7874 0.4064)
			(end 0.7874 -0.4064)
			(stroke
				(width 0.1524)
				(type default)
			)
			(layer "B.SilkS")
		)
		(fp_line
			(start -0.7874 -0.4064)
			(end -0.7874 0.4064)
			(stroke
				(width 0.1524)
				(type default)
			)
			(layer "B.SilkS")
		)
		(fp_line
			(start 0.7874 -0.4064)
			(end -0.7874 -0.4064)
			(stroke
				(width 0.1524)
				(type default)
			)
			(layer "B.SilkS")
		)
		(fp_line
			(start -0.67945 0.3048)
			(end -0.120396 0.3048)
			(stroke
				(width 0.1)
				(type default)
			)
			(layer "B.Fab")
		)
		(fp_line
			(start -0.120396 0.3048)
			(end -0.120396 0.2794)
			(stroke
				(width 0.1)
				(type default)
			)
			(layer "B.Fab")
		)
		(fp_line
			(start 0.12065 0.3048)
			(end 0.67945 0.3048)
			(stroke
				(width 0.1)
				(type default)
			)
			(layer "B.Fab")
		)
		(fp_line
			(start 0.67945 0.3048)
			(end 0.67945 -0.305054)
			(stroke
				(width 0.1)
				(type default)
			)
			(layer "B.Fab")
		)
		(fp_line
			(start -0.120396 0.2794)
			(end 0.12065 0.2794)
			(stroke
				(width 0.1)
				(type default)
			)
			(layer "B.Fab")
		)
		(fp_line
			(start 0.12065 0.2794)
			(end 0.12065 0.3048)
			(stroke
				(width 0.1)
				(type default)
			)
			(layer "B.Fab")
		)
		(fp_line
			(start -0.12065 -0.2794)
			(end -0.12065 -0.3048)
			(stroke
				(width 0.1)
				(type default)
			)
			(layer "B.Fab")
		)
		(fp_line
			(start 0.12065 -0.2794)
			(end -0.12065 -0.2794)
			(stroke
				(width 0.1)
				(type default)
			)
			(layer "B.Fab")
		)
		(fp_line
			(start -0.67945 -0.3048)
			(end -0.67945 0.3048)
			(stroke
				(width 0.1)
				(type default)
			)
			(layer "B.Fab")
		)
		(fp_line
			(start -0.12065 -0.3048)
			(end -0.67945 -0.3048)
			(stroke
				(width 0.1)
				(type default)
			)
			(layer "B.Fab")
		)
		(fp_line
			(start 0.12065 -0.305054)
			(end 0.12065 -0.2794)
			(stroke
				(width 0.1)
				(type default)
			)
			(layer "B.Fab")
		)
		(fp_line
			(start 0.67945 -0.305054)
			(end 0.12065 -0.305054)
			(stroke
				(width 0.1)
				(type default)
			)
			(layer "B.Fab")
		)
		(pad "1" smd circle
			(at 0.40005 0 90)
			(size 0 0)
			(layers "B.Cu" "B.Mask" "B.Paste")
			(net "PVCCIN_CPU0_PVCC")
		)
		(pad "2" smd circle
			(at -0.40005 0 90)
			(size 0 0)
			(layers "B.Cu" "B.Mask" "B.Paste")
			(net "PVCCIN_CPU0_VDD3")
		)
	)
)
